# T6G (Grand Teton) — schematic netlist excerpt (pin names and nets, part order shuffled) for the footprints in the layout excerpt that follows; sources: Cadence DE-HDL packaged netlist, KiCad conversion of 04192023_DAF0TMB3IC0_F0TG_MB_C_brd_V02_OCP.brd

C2226  Q_CAP  22UF 4V 20% X6S  pkg C0402  page 69 : A = PVDDCR_CPU1_P0 ; B = GND
R4162  Q_RES  54.9K 1% EMPTY  pkg 0402LF  page 124 : A = P3V3_AUX ; B = GPU_3V3IO_RSVD3

(kicad_pcb
	(version 20260206)
	(generator "pcbnew")
	(generator_version "10.0")
	(general
		(thickness 1.6)
		(legacy_teardrops no)
	)
	(paper "A4")
	(title_block
		(title "04192023_DAF0TMB3IC0_F0TG_MB_C_brd_V02_OCP.brd")
		(comment 1 "Grand Teton / footprints 8192-8193 of 8354")
	)
	(layers
		(0 "F.Cu" signal "TOP")
		(4 "In1.Cu" signal "GND")
		(6 "In2.Cu" signal "IN1")
		(8 "In3.Cu" signal "GND1")
		(10 "In4.Cu" signal "IN2")
		(12 "In5.Cu" signal "GND2")
		(14 "In6.Cu" signal "IN3")
		(16 "In7.Cu" signal "GND3")
		(18 "In8.Cu" signal "VCC")
		(20 "In9.Cu" signal "VCC1")
		(22 "In10.Cu" signal "GND4")
		(24 "In11.Cu" signal "IN4")
		(26 "In12.Cu" signal "GND5")
		(28 "In13.Cu" signal "IN5")
		(30 "In14.Cu" signal "GND6")
		(32 "In15.Cu" signal "IN6")
		(34 "In16.Cu" signal "GND7")
		(2 "B.Cu" signal "BOTTOM")
		(9 "F.Adhes" user "F.Adhesive")
		(11 "B.Adhes" user "B.Adhesive")
		(13 "F.Paste" user "Package Geometry/Pastemask Top")
		(15 "B.Paste" user "Package Geometry/Pastemask Bottom")
		(5 "F.SilkS" user "Ref Des/Silkscreen Top")
		(7 "B.SilkS" user "Ref Des/Silkscreen Bottom")
		(1 "F.Mask" user "Board Geometry/Soldermask Top")
		(3 "B.Mask" user "Board Geometry/Soldermask Bottom")
		(17 "Dwgs.User" user "User.Drawings")
		(19 "Cmts.User" user "User.Comments")
		(21 "Eco1.User" user "User.Eco1")
		(23 "Eco2.User" user "User.Eco2")
		(25 "Edge.Cuts" user "Board Geometry/Outline")
		(27 "Margin" user)
		(31 "F.CrtYd" user "Package Geometry/Place Bound Top")
		(29 "B.CrtYd" user "Package Geometry/Place Bound Bottom")
		(35 "F.Fab" user "Ref Des/Assembly Top")
		(33 "B.Fab" user "Ref Des/Assembly Bottom")
	)
	(footprint ""
		(layer "B.Cu")
		(at 429.103282 -436.414672 -90)
		(property "Reference" "R4162"
			(at 0 0 90)
			(layer "B.SilkS")
			(hide yes)
			(effects
				(font
					(size 1.27 1.27)
				)
				(justify mirror)
			)
		)
		(property "Value" ""
			(at 0 0 90)
			(layer "B.Fab")
			(effects
				(font
					(size 1.27 1.27)
				)
				(justify mirror)
			)
		)
		(duplicate_pad_numbers_are_jumpers no)
		(fp_line
			(start -0.7874 0.4064)
			(end 0.7874 0.4064)
			(stroke
				(width 0.1524)
				(type default)
			)
			(layer "B.SilkS")
		)
		(fp_line
			(start 0.7874 0.4064)
			(end 0.7874 -0.4064)
			(stroke
				(width 0.1524)
				(type default)
			)
			(layer "B.SilkS")
		)
		(fp_line
			(start -0.7874 -0.4064)
			(end -0.7874 0.4064)
			(stroke
				(width 0.1524)
				(type default)
			)
			(layer "B.SilkS")
		)
		(fp_line
			(start 0.7874 -0.4064)
			(end -0.7874 -0.4064)
			(stroke
				(width 0.1524)
				(type default)
			)
			(layer "B.SilkS")
		)
		(fp_line
			(start -0.67945 0.3048)
			(end -0.120396 0.3048)
			(stroke
				(width 0.1)
				(type default)
			)
			(layer "B.Fab")
		)
		(fp_line
			(start -0.120396 0.3048)
			(end -0.120396 0.2794)
			(stroke
				(width 0.1)
				(type default)
			)
			(layer "B.Fab")
		)
		(fp_line
			(start 0.12065 0.3048)
			(end 0.67945 0.3048)
			(stroke
				(width 0.1)
				(type default)
			)
			(layer "B.Fab")
		)
		(fp_line
			(start 0.67945 0.3048)
			(end 0.67945 -0.305054)
			(stroke
				(width 0.1)
				(type default)
			)
			(layer "B.Fab")
		)
		(fp_line
			(start -0.120396 0.2794)
			(end 0.12065 0.2794)
			(stroke
				(width 0.1)
				(type default)
			)
			(layer "B.Fab")
		)
		(fp_line
			(start 0.12065 0.2794)
			(end 0.12065 0.3048)
			(stroke
				(width 0.1)
				(type default)
			)
			(layer "B.Fab")
		)
		(fp_line
			(start -0.12065 -0.2794)
			(end -0.12065 -0.3048)
			(stroke
				(width 0.1)
				(type default)
			)
			(layer "B.Fab")
		)
		(fp_line
			(start 0.12065 -0.2794)
			(end -0.12065 -0.2794)
			(stroke
				(width 0.1)
				(type default)
			)
			(layer "B.Fab")
		)
		(fp_line
			(start -0.67945 -0.3048)
			(end -0.67945 0.3048)
			(stroke
				(width 0.1)
				(type default)
			)
			(layer "B.Fab")
		)
		(fp_line
			(start -0.12065 -0.3048)
			(end -0.67945 -0.3048)
			(stroke
				(width 0.1)
				(type default)
			)
			(layer "B.Fab")
		)
		(fp_line
			(start 0.12065 -0.305054)
			(end 0.12065 -0.2794)
			(stroke
				(width 0.1)
				(type default)
			)
			(layer "B.Fab")
		)
		(fp_line
			(start 0.67945 -0.305054)
			(end 0.12065 -0.305054)
			(stroke
				(width 0.1)
				(type default)
			)
			(layer "B.Fab")
		)
		(pad "1" smd circle
			(at 0.40005 0 90)
			(size 0 0)
			(layers "B.Cu" "B.Mask" "B.Paste")
			(net "P3V3_AUX")
		)
		(pad "2" smd circle
			(at -0.40005 0 90)
			(size 0 0)
			(layers "B.Cu" "B.Mask" "B.Paste")
			(net "GPU_3V3IO_RSVD3")
		)
	)
	(footprint ""
		(layer "B.Cu")
		(at 355.803454 -268.41831)
		(property "Reference" "C2226"
			(at 0 0 0)
			(layer "B.SilkS")
			(hide yes)
			(effects
				(font
					(size 1.27 1.27)
				)
				(justify mirror)
			)
		)
		(property "Value" ""
			(at 0 0 0)
			(layer "B.Fab")
			(effects
				(font
					(size 1.27 1.27)
				)
				(justify mirror)
			)
		)
		(duplicate_pad_numbers_are_jumpers no)
		(fp_line
			(start -0.7874 -0.4064)
			(end -0.7874 0.4064)
			(stroke
				(width 0.1524)
				(type default)
			)
			(layer "B.SilkS")
		)
		(fp_line
			(start -0.7874 0.4064)
			(end 0.7874 0.4064)
			(stroke
				(width 0.1524)
				(type default)
			)
			(layer "B.SilkS")
		)
		(fp_line
			(start 0.7874 -0.4064)
			(end -0.7874 -0.4064)
			(stroke
				(width 0.1524)
				(type default)
			)
			(layer "B.SilkS")
		)
		(fp_line
			(start 0.7874 0.4064)
			(end 0.7874 -0.4064)
			(stroke
				(width 0.1524)
				(type default)
			)
			(layer "B.SilkS")
		)
		(fp_line
			(start -0.67945 -0.3048)
			(end -0.67945 0.3048)
			(stroke
				(width 0.1)
				(type default)
			)
			(layer "B.Fab")
		)
		(fp_line
			(start -0.67945 0.3048)
			(end -0.120396 0.3048)
			(stroke
				(width 0.1)
				(type default)
			)
			(layer "B.Fab")
		)
		(fp_line
			(start -0.12065 -0.3048)
			(end -0.67945 -0.3048)
			(stroke
				(width 0.1)
				(type default)
			)
			(layer "B.Fab")
		)
		(fp_line
			(start -0.12065 -0.2794)
			(end -0.12065 -0.3048)
			(stroke
				(width 0.1)
				(type default)
			)
			(layer "B.Fab")
		)
		(fp_line
			(start -0.120396 0.2794)
			(end 0.12065 0.2794)
			(stroke
				(width 0.1)
				(type default)
			)
			(layer "B.Fab")
		)
		(fp_line
			(start -0.120396 0.3048)
			(end -0.120396 0.2794)
			(stroke
				(width 0.1)
				(type default)
			)
			(layer "B.Fab")
		)
		(fp_line
			(start 0.12065 -0.305054)
			(end 0.12065 -0.2794)
			(stroke
				(width 0.1)
				(type default)
			)
			(layer "B.Fab")
		)
		(fp_line
			(start 0.12065 -0.2794)
			(end -0.12065 -0.2794)
			(stroke
				(width 0.1)
				(type default)
			)
			(layer "B.Fab")
		)
		(fp_line
			(start 0.12065 0.2794)
			(end 0.12065 0.3048)
			(stroke
				(width 0.1)
				(type default)
			)
			(layer "B.Fab")
		)
		(fp_line
			(start 0.12065 0.3048)
			(end 0.67945 0.3048)
			(stroke
				(width 0.1)
				(type default)
			)
			(layer "B.Fab")
		)
		(fp_line
			(start 0.67945 -0.305054)
			(end 0.12065 -0.305054)
			(stroke
				(width 0.1)
				(type default)
			)
			(layer "B.Fab")
		)
		(fp_line
			(start 0.67945 0.3048)
			(end 0.67945 -0.305054)
			(stroke
				(width 0.1)
				(type default)
			)
			(layer "B.Fab")
		)
		(pad "1" smd circle
			(at 0.40005 0 180)
			(size 0 0)
			(layers "B.Cu" "B.Mask" "B.Paste")
			(net "PVDDCR_CPU1_P0")
		)
		(pad "2" smd circle
			(at -0.40005 0 180)
			(size 0 0)
			(layers "B.Cu" "B.Mask" "B.Paste")
			(net "GND")
		)
	)
)
